# BASEBOARD_FAB2 (Tioga Pass) — schematic netlist excerpt (pin names and nets, part order shuffled) for the footprints in the layout excerpt that follows; sources: Cadence DE-HDL packaged netlist, KiCad conversion of Wiwynn_Tioga_Pass_MB.brd

D25W8  RB551V30-GP  pkg DISCRET-G  page 252 : ANODE = P5V ; CATHODE = P5V_VGA_D
C2L16  CAP_A  0.01UF 25V 10% X7R  pkg 0402V  page 173 : A = SATA6G_PCH_PCIE_UP_SATA_RXP<6> ; B = SATA6G_P6_RX_C_DP

U1M5  74CBTLV1G125  IC  pkg SMLF  page 113
  OE_N  = FM_CPU0_OR_CPU1_MCP_PRES
  A  = P1V8_MCP_CPU0
  B  = JTAG_MCP_TMS_R1

(kicad_pcb
	(version 20260206)
	(generator "pcbnew")
	(generator_version "10.0")
	(general
		(thickness 1.6)
		(legacy_teardrops no)
	)
	(paper "A4")
	(title_block
		(title "Wiwynn_Tioga_Pass_MB.brd")
		(comment 1 "Tioga Pass / footprints 4724-4726 of 4770")
	)
	(layers
		(0 "F.Cu" signal "TOP")
		(4 "In1.Cu" signal "L2GND")
		(6 "In2.Cu" signal "L3")
		(8 "In3.Cu" signal "L4GND")
		(10 "In4.Cu" signal "L5")
		(12 "In5.Cu" signal "L6GND")
		(14 "In6.Cu" signal "L7VCC")
		(16 "In7.Cu" signal "L8VCC")
		(18 "In8.Cu" signal "L9GND")
		(20 "In9.Cu" signal "L10")
		(22 "In10.Cu" signal "L11GND")
		(24 "In11.Cu" signal "L12")
		(26 "In12.Cu" signal "L13GND")
		(2 "B.Cu" signal "BOTTOM")
		(9 "F.Adhes" user "F.Adhesive")
		(11 "B.Adhes" user "B.Adhesive")
		(13 "F.Paste" user "Package Geometry/Pastemask Top")
		(15 "B.Paste" user "Package Geometry/Pastemask Bottom")
		(5 "F.SilkS" user "Ref Des/Silkscreen Top")
		(7 "B.SilkS" user "Ref Des/Silkscreen Bottom")
		(1 "F.Mask" user "Board Geometry/Soldermask Top")
		(3 "B.Mask" user "Board Geometry/Soldermask Bottom")
		(17 "Dwgs.User" user "User.Drawings")
		(19 "Cmts.User" user "User.Comments")
		(21 "Eco1.User" user "User.Eco1")
		(23 "Eco2.User" user "User.Eco2")
		(25 "Edge.Cuts" user "Board Geometry/Outline")
		(27 "Margin" user)
		(31 "F.CrtYd" user "Package Geometry/Place Bound Top")
		(29 "B.CrtYd" user "Package Geometry/Place Bound Bottom")
		(35 "F.Fab" user "Ref Des/Assembly Top")
		(33 "B.Fab" user "Ref Des/Assembly Bottom")
	)
	(footprint ""
		(layer "B.Cu")
		(at 454.4822 -128.6764 -90)
		(property "Reference" "U1M5"
			(at 1.4986 3.64109 270)
			(unlocked yes)
			(layer "B.SilkS")
			(effects
				(font
					(size 0.7874 0.5842)
					(thickness 0.1524)
				)
				(justify left mirror)
			)
		)
		(property "Value" ""
			(at 0 0 90)
			(layer "B.Fab")
			(effects
				(font
					(size 1.27 1.27)
				)
				(justify mirror)
			)
		)
		(duplicate_pad_numbers_are_jumpers no)
		(fp_circle
			(center 0.4699 -0.8382)
			(end 0.4699 -0.9652)
			(stroke
				(width 0.254)
				(type default)
			)
			(fill no)
			(layer "B.SilkS")
		)
		(fp_poly
			(pts
				(xy -0.21463 -0.450088) (xy -1.56337 -0.450088) (xy -1.56337 1.75006) (xy -0.21463 1.75006)
			)
			(stroke
				(width 0)
				(type default)
			)
			(fill no)
			(layer "B.CrtYd")
		)
		(fp_line
			(start -1.56337 1.75006)
			(end -0.21463 1.75006)
			(stroke
				(width 0.1)
				(type default)
			)
			(layer "B.Fab")
		)
		(fp_line
			(start -0.21463 1.75006)
			(end -0.21463 -0.450088)
			(stroke
				(width 0.1)
				(type default)
			)
			(layer "B.Fab")
		)
		(fp_line
			(start -1.56337 -0.450088)
			(end -1.56337 1.75006)
			(stroke
				(width 0.1)
				(type default)
			)
			(layer "B.Fab")
		)
		(fp_line
			(start -0.21463 -0.450088)
			(end -1.56337 -0.450088)
			(stroke
				(width 0.1)
				(type default)
			)
			(layer "B.Fab")
		)
		(fp_circle
			(center 0.4699 -0.8382)
			(end 0.4699 -0.9652)
			(stroke
				(width 0.254)
				(type default)
			)
			(fill no)
			(layer "B.Fab")
		)
		(pad "1" smd rect
			(at 0 0 90)
			(size 1.016 0.381)
			(layers "B.Cu" "B.Mask" "B.Paste")
			(net "FM_CPU0_OR_CPU1_MCP_PRES")
		)
		(pad "2" smd rect
			(at 0 0.649986 90)
			(size 1.016 0.381)
			(layers "B.Cu" "B.Mask" "B.Paste")
			(net "P1V8_MCP_CPU0")
		)
		(pad "3" smd rect
			(at 0 1.299972 90)
			(size 1.016 0.381)
			(layers "B.Cu" "B.Mask" "B.Paste")
			(net "GND")
		)
		(pad "4" smd rect
			(at -1.778 1.299972 90)
			(size 1.016 0.381)
			(layers "B.Cu" "B.Mask" "B.Paste")
			(net "JTAG_MCP_TMS_R1")
		)
		(pad "5" smd rect
			(at -1.778 0 90)
			(size 1.016 0.381)
			(layers "B.Cu" "B.Mask" "B.Paste")
			(net "P3V3_STBY")
		)
	)
	(footprint ""
		(layer "B.Cu")
		(at 408.305 -150.622 90)
		(property "Reference" "C2L16"
			(at 0 0 90)
			(layer "B.SilkS")
			(hide yes)
			(effects
				(font
					(size 1.27 1.27)
				)
				(justify mirror)
			)
		)
		(property "Value" ""
			(at 0 0 90)
			(layer "B.Fab")
			(effects
				(font
					(size 1.27 1.27)
				)
				(justify mirror)
			)
		)
		(duplicate_pad_numbers_are_jumpers no)
		(fp_poly
			(pts
				(xy -0.3048 -0.1016) (xy -0.3048 0.9906) (xy 0.3048 0.9906) (xy 0.3048 -0.1016)
			)
			(stroke
				(width 0)
				(type default)
			)
			(fill no)
			(layer "B.CrtYd")
		)
		(fp_line
			(start 0.3048 -0.1016)
			(end 0.3048 0.9906)
			(stroke
				(width 0.1)
				(type default)
			)
			(layer "B.Fab")
		)
		(fp_line
			(start -0.3048 -0.1016)
			(end 0.3048 -0.1016)
			(stroke
				(width 0.1)
				(type default)
			)
			(layer "B.Fab")
		)
		(fp_line
			(start 0.3048 0.9906)
			(end -0.3048 0.9906)
			(stroke
				(width 0.1)
				(type default)
			)
			(layer "B.Fab")
		)
		(fp_line
			(start -0.3048 0.9906)
			(end -0.3048 -0.1016)
			(stroke
				(width 0.1)
				(type default)
			)
			(layer "B.Fab")
		)
		(pad "1" smd rect
			(at 0 0 270)
			(size 0.508 0.508)
			(layers "B.Cu" "B.Mask" "B.Paste")
			(net "SATA6G_PCH_PCIE_UP_SATA_RXP<6>")
		)
		(pad "2" smd rect
			(at 0 0.889 270)
			(size 0.508 0.508)
			(layers "B.Cu" "B.Mask" "B.Paste")
			(net "SATA6G_P6_RX_C_DP")
		)
		(zone
			(layer "B.Cu")
			(hatch none 0.5)
			(connect_pads
				(clearance 0)
			)
			(min_thickness 0.25)
			(keepout
				(tracks allowed)
				(vias not_allowed)
				(pads allowed)
				(copperpour not_allowed)
				(footprints allowed)
			)
			(placement
				(enabled no)
				(sheetname "")
			)
			(fill
				(thermal_gap 0.5)
				(thermal_bridge_width 0.5)
				(island_removal_mode 0)
			)
			(polygon
				(pts
					(xy 408.559 -150.876) (xy 408.559 -150.368) (xy 408.94 -150.368) (xy 408.94 -150.876)
				)
			)
		)
		(zone
			(layer "B.Cu")
			(hatch none 0.5)
			(connect_pads
				(clearance 0)
			)
			(min_thickness 0.25)
			(keepout
				(tracks not_allowed)
				(vias allowed)
				(pads allowed)
				(copperpour not_allowed)
				(footprints allowed)
			)
			(placement
				(enabled no)
				(sheetname "")
			)
			(fill
				(thermal_gap 0.5)
				(thermal_bridge_width 0.5)
				(island_removal_mode 0)
			)
			(polygon
				(pts
					(xy 408.94 -150.876) (xy 408.94 -150.368) (xy 408.559 -150.368) (xy 408.559 -150.876)
				)
			)
		)
	)
	(footprint ""
		(layer "B.Cu")
		(at 484.251 -55.6641)
		(property "Reference" "D25W8"
			(at 0 0 0)
			(layer "B.SilkS")
			(hide yes)
			(effects
				(font
					(size 1.27 1.27)
				)
				(justify mirror)
			)
		)
		(property "Value" "*"
			(at 0 -6.8961 0)
			(unlocked yes)
			(layer "B.Fab")
			(hide yes)
			(effects
				(font
					(size 1.27 1.016)
					(thickness 0.1524)
				)
				(justify mirror)
			)
		)
		(property "Device Type" "RB551V30-GP_DISCRET-G-RB551V30A"
			(at 0 -8.8011 0)
			(unlocked yes)
			(layer "B.Fab")
			(hide yes)
			(effects
				(font
					(size 1.27 1.016)
					(thickness 0.1524)
				)
				(justify mirror)
			)
		)
		(duplicate_pad_numbers_are_jumpers no)
		(fp_line
			(start -0.889 -1.9304)
			(end -0.889 2.159)
			(stroke
				(width 0.1524)
				(type default)
			)
			(layer "B.SilkS")
		)
		(fp_line
			(start -0.889 2.159)
			(end 0.889 2.159)
			(stroke
				(width 0.1524)
				(type default)
			)
			(layer "B.SilkS")
		)
		(fp_line
			(start -0.762 2.0574)
			(end 0.762 2.0574)
			(stroke
				(width 0.508)
				(type default)
			)
			(layer "B.SilkS")
		)
		(fp_line
			(start 0.889 -1.9304)
			(end -0.889 -1.9304)
			(stroke
				(width 0.1524)
				(type default)
			)
			(layer "B.SilkS")
		)
		(fp_line
			(start 0.889 2.159)
			(end 0.889 -1.9304)
			(stroke
				(width 0.1524)
				(type default)
			)
			(layer "B.SilkS")
		)
		(fp_rect
			(start 1.016 2.3114)
			(end -1.016 -2.0066)
			(stroke
				(width 0)
				(type default)
			)
			(fill no)
			(layer "B.CrtYd")
		)
		(fp_poly
			(pts
				(xy 1.016 -2.0066) (xy -1.016 -2.0066) (xy -1.016 2.3114) (xy 1.016 2.3114)
			)
			(stroke
				(width 0)
				(type default)
			)
			(fill no)
			(layer "B.Fab")
		)
		(pad "A" smd rect
			(at 0 -1.143 180)
			(size 0.5588 1.016)
			(layers "B.Cu" "B.Mask" "B.Paste")
			(net "P5V")
		)
		(pad "K" smd rect
			(at 0 1.143 180)
			(size 0.5588 1.016)
			(layers "B.Cu" "B.Mask" "B.Paste")
			(net "P5V_VGA_D")
		)
	)
)
